(kicad_pcb
	(version 20211014)
	(generator pcbnew)
	(general
    (thickness 1.6)
  )
	(paper "A4")
	(title_block
    (title "SA800U (Snapdragon 845) Baseboard")
    (date "2023-10-19")
    (rev "1.0.3")
    (company "Antmicro Ltd.")
    (comment 1 "www.antmicro.com")
		(comment 9 "footprints 487-490 of 589")
	)
	(layers
    (0 "F.Cu" signal)
    (1 "In1.Cu" power)
    (2 "In2.Cu" signal)
    (3 "In3.Cu" signal)
    (4 "In4.Cu" power)
    (31 "B.Cu" signal)
    (32 "B.Adhes" user "B.Adhesive")
    (33 "F.Adhes" user "F.Adhesive")
    (34 "B.Paste" user)
    (35 "F.Paste" user)
    (36 "B.SilkS" user "B.Silkscreen")
    (37 "F.SilkS" user "F.Silkscreen")
    (38 "B.Mask" user)
    (39 "F.Mask" user)
    (40 "Dwgs.User" user "User.Drawings")
    (41 "Cmts.User" user "User.Comments")
    (42 "Eco1.User" user "User.Eco1")
    (43 "Eco2.User" user "User.Eco2")
    (44 "Edge.Cuts" user)
    (45 "Margin" user)
    (46 "B.CrtYd" user "B.Courtyard")
    (47 "F.CrtYd" user "F.Courtyard")
    (48 "B.Fab" user)
    (49 "F.Fab" user)
  )
	(footprint "sa800u-baseboard-hw-footprints:Bus_M.2_Socket_Key_M_Amphenol_MDT580M01001" locked (layer "B.Cu")
    (tedit 5E81ED22)
    (at 146.192 100.36 90)
    (property "Author" "Antmicro")
    (property "License" "Apache-2.0")
    (property "MPN" "MDT580M01001")
    (property "Manufacturer" "Amphenol")
    (property "Sheetfile" "m2.kicad_sch")
    (property "Sheetname" "M2")
    (attr smd)
    (fp_text reference "U15" (at -0.3 5.978 90) (layer "B.SilkS")
      (effects (font (size 0.7 0.7) (thickness 0.15)) (justify right bottom mirror))
    )
    (fp_text value "Bus_M.2_MDT580M01001" (at 0 -5.9 90) (layer "B.Fab")
      (effects (font (size 0.7 0.7) (thickness 0.15)) (justify right bottom mirror))
    )
    (fp_text user "Author: Antmicro" (at -13 -8.499 90) (layer "B.Fab") hide
      (effects (font (size 0.7 0.7) (thickness 0.15)) (justify right bottom mirror))
    )
    (fp_text user "${REFERENCE}" (at -13 -9.698 90) (layer "B.Fab") hide
      (effects (font (size 0.7 0.7) (thickness 0.15)) (justify right bottom mirror))
    )
    (fp_text user "License: Apache-2.0" (at -13 -10.899 90) (layer "B.Fab") hide
      (effects (font (size 0.7 0.7) (thickness 0.15)) (justify right bottom mirror))
    )
    (fp_line (start -10.071 -0.624) (end 9.499 -0.624) (layer "B.SilkS") (width 0.15))
    (fp_line (start -10.071 -4.626) (end -11.151 -4.626) (layer "B.SilkS") (width 0.15))
    (fp_line (start 10.848 -4.626) (end 9.768 -4.626) (layer "B.SilkS") (width 0.15))
    (fp_line (start -10.071 -4.626) (end -10.071 -2.205) (layer "B.SilkS") (width 0.15))
    (fp_line (start 9.768 -4.626) (end 9.768 -2.346) (layer "B.SilkS") (width 0.15))
    (fp_circle (center -9.7 4.7) (end -9.65 4.7) (layer "B.SilkS") (width 0.15) (fill solid))
    (fp_rect (start -11.5 5) (end 11.5 -4.9) (layer "B.CrtYd") (width 0.05) (fill none))
    (fp_line (start -10.985 4.13) (end -10.859 4.255) (layer "B.Fab") (width 0.15))
    (fp_rect (start -11 -4.275) (end 10.999 4.276) (layer "B.Fab") (width 0.15) (fill none))
    (pad "" np_thru_hole circle locked (at -10 -1.425 90) (size 1.1 1.1) (drill 1.1) (layers F&B.Cu *.Mask))
    (pad "" np_thru_hole circle locked (at 9.999 -1.425 90) (size 1.6 1.6) (drill 1.6) (layers F&B.Cu *.Mask))
    (pad "1" smd rect locked (at -9.25 3.848 90) (size 0.3 1.55) (layers "B.Cu" "B.Paste" "B.Mask")
      (net 1 "GND") (pinfunction "GND") (pintype "passive"))
    (pad "2" smd rect locked (at -9 -3.7 90) (size 0.3 1.55) (layers "B.Cu" "B.Paste" "B.Mask")
      (net 131 "3V3_SYS") (pinfunction "3V3") (pintype "passive"))
    (pad "3" smd rect locked (at -8.75 3.848 90) (size 0.3 1.55) (layers "B.Cu" "B.Paste" "B.Mask")
      (net 1 "GND") (pinfunction "GND") (pintype "passive"))
    (pad "4" smd rect locked (at -8.5 -3.7 90) (size 0.3 1.55) (layers "B.Cu" "B.Paste" "B.Mask")
      (net 131 "3V3_SYS") (pinfunction "3V3") (pintype "passive"))
    (pad "5" smd rect locked (at -8.25 3.848 90) (size 0.3 1.55) (layers "B.Cu" "B.Paste" "B.Mask")
      (net 656 "unconnected-(U15-Pad5)") (pinfunction "PER3_N") (pintype "passive+no_connect"))
    (pad "6" smd rect locked (at -8 -3.7 90) (size 0.3 1.55) (layers "B.Cu" "B.Paste" "B.Mask")
      (net 655 "unconnected-(U15-Pad6)") (pinfunction "NC") (pintype "no_connect"))
    (pad "7" smd rect locked (at -7.75 3.848 90) (size 0.3 1.55) (layers "B.Cu" "B.Paste" "B.Mask")
      (net 654 "unconnected-(U15-Pad7)") (pinfunction "PER3_P") (pintype "passive+no_connect"))
    (pad "8" smd rect locked (at -7.5 -3.7 90) (size 0.3 1.55) (layers "B.Cu" "B.Paste" "B.Mask")
      (net 653 "unconnected-(U15-Pad8)") (pinfunction "NC") (pintype "no_connect"))
    (pad "9" smd rect locked (at -7.25 3.848 90) (size 0.3 1.55) (layers "B.Cu" "B.Paste" "B.Mask")
      (net 1 "GND") (pinfunction "GND") (pintype "passive"))
    (pad "10" smd rect locked (at -7 -3.7 90) (size 0.3 1.55) (layers "B.Cu" "B.Paste" "B.Mask")
      (net 374 "Net-(D21-Pad2)") (pinfunction "LED") (pintype "passive"))
    (pad "11" smd rect locked (at -6.75 3.848 90) (size 0.3 1.55) (layers "B.Cu" "B.Paste" "B.Mask")
      (net 652 "unconnected-(U15-Pad11)") (pinfunction "PET3_N") (pintype "passive+no_connect"))
    (pad "12" smd rect locked (at -6.5 -3.7 90) (size 0.3 1.55) (layers "B.Cu" "B.Paste" "B.Mask")
      (net 131 "3V3_SYS") (pinfunction "3V3") (pintype "passive"))
    (pad "13" smd rect locked (at -6.25 3.848 90) (size 0.3 1.55) (layers "B.Cu" "B.Paste" "B.Mask")
      (net 651 "unconnected-(U15-Pad13)") (pinfunction "PET3_P") (pintype "passive+no_connect"))
    (pad "14" smd rect locked (at -6 -3.7 90) (size 0.3 1.55) (layers "B.Cu" "B.Paste" "B.Mask")
      (net 131 "3V3_SYS") (pinfunction "3V3") (pintype "passive"))
    (pad "15" smd rect locked (at -5.75 3.848 90) (size 0.3 1.55) (layers "B.Cu" "B.Paste" "B.Mask")
      (net 1 "GND") (pinfunction "GND") (pintype "passive"))
    (pad "16" smd rect locked (at -5.5 -3.7 90) (size 0.3 1.55) (layers "B.Cu" "B.Paste" "B.Mask")
      (net 131 "3V3_SYS") (pinfunction "3V3") (pintype "passive"))
    (pad "17" smd rect locked (at -5.25 3.848 90) (size 0.3 1.55) (layers "B.Cu" "B.Paste" "B.Mask")
      (net 650 "unconnected-(U15-Pad17)") (pinfunction "PER2_N") (pintype "passive+no_connect"))
    (pad "18" smd rect locked (at -5 -3.7 90) (size 0.3 1.55) (layers "B.Cu" "B.Paste" "B.Mask")
      (net 131 "3V3_SYS") (pinfunction "3V3") (pintype "passive"))
    (pad "19" smd rect locked (at -4.75 3.848 90) (size 0.3 1.55) (layers "B.Cu" "B.Paste" "B.Mask")
      (net 649 "unconnected-(U15-Pad19)") (pinfunction "PER2_P") (pintype "passive+no_connect"))
    (pad "20" smd rect locked (at -4.5 -3.7 90) (size 0.3 1.55) (layers "B.Cu" "B.Paste" "B.Mask")
      (net 648 "unconnected-(U15-Pad20)") (pinfunction "NC") (pintype "no_connect"))
    (pad "21" smd rect locked (at -4.25 3.848 90) (size 0.3 1.55) (layers "B.Cu" "B.Paste" "B.Mask")
      (net 1 "GND") (pinfunction "GND") (pintype "passive"))
    (pad "22" smd rect locked (at -4 -3.7 90) (size 0.3 1.55) (layers "B.Cu" "B.Paste" "B.Mask")
      (net 647 "unconnected-(U15-Pad22)") (pinfunction "NC") (pintype "no_connect"))
    (pad "23" smd rect locked (at -3.75 3.848 90) (size 0.3 1.55) (layers "B.Cu" "B.Paste" "B.Mask")
      (net 646 "unconnected-(U15-Pad23)") (pinfunction "PET2_N") (pintype "passive+no_connect"))
    (pad "24" smd rect locked (at -3.5 -3.7 90) (size 0.3 1.55) (layers "B.Cu" "B.Paste" "B.Mask")
      (net 645 "unconnected-(U15-Pad24)") (pinfunction "NC") (pintype "no_connect"))
    (pad "25" smd rect locked (at -3.25 3.848 90) (size 0.3 1.55) (layers "B.Cu" "B.Paste" "B.Mask")
      (net 644 "unconnected-(U15-Pad25)") (pinfunction "PET2_P") (pintype "passive+no_connect"))
    (pad "26" smd rect locked (at -3 -3.7 90) (size 0.3 1.55) (layers "B.Cu" "B.Paste" "B.Mask")
      (net 643 "unconnected-(U15-Pad26)") (pinfunction "NC") (pintype "no_connect"))
    (pad "27" smd rect locked (at -2.75 3.848 90) (size 0.3 1.55) (layers "B.Cu" "B.Paste" "B.Mask")
      (net 1 "GND") (pinfunction "GND") (pintype "passive"))
    (pad "28" smd rect locked (at -2.5 -3.7 90) (size 0.3 1.55) (layers "B.Cu" "B.Paste" "B.Mask")
      (net 642 "unconnected-(U15-Pad28)") (pinfunction "NC") (pintype "no_connect"))
    (pad "29" smd rect locked (at -2.25 3.848 90) (size 0.3 1.55) (layers "B.Cu" "B.Paste" "B.Mask")
      (net 641 "unconnected-(U15-Pad29)") (pinfunction "PER1_N") (pintype "passive+no_connect"))
    (pad "30" smd rect locked (at -2 -3.7 90) (size 0.3 1.55) (layers "B.Cu" "B.Paste" "B.Mask")
      (net 640 "unconnected-(U15-Pad30)") (pinfunction "NC") (pintype "no_connect"))
    (pad "31" smd rect locked (at -1.75 3.848 90) (size 0.3 1.55) (layers "B.Cu" "B.Paste" "B.Mask")
      (net 639 "unconnected-(U15-Pad31)") (pinfunction "PER1_P") (pintype "passive+no_connect"))
    (pad "32" smd rect locked (at -1.5 -3.7 90) (size 0.3 1.55) (layers "B.Cu" "B.Paste" "B.Mask")
      (net 638 "unconnected-(U15-Pad32)") (pinfunction "NC") (pintype "no_connect"))
    (pad "33" smd rect locked (at -1.25 3.848 90) (size 0.3 1.55) (layers "B.Cu" "B.Paste" "B.Mask")
      (net 1 "GND") (pinfunction "GND") (pintype "passive"))
    (pad "34" smd rect locked (at -1 -3.7 90) (size 0.3 1.55) (layers "B.Cu" "B.Paste" "B.Mask")
      (net 637 "unconnected-(U15-Pad34)") (pinfunction "NC") (pintype "no_connect"))
    (pad "35" smd rect locked (at -0.75 3.848 90) (size 0.3 1.55) (layers "B.Cu" "B.Paste" "B.Mask")
      (net 636 "unconnected-(U15-Pad35)") (pinfunction "PET1_N") (pintype "passive+no_connect"))
    (pad "36" smd rect locked (at -0.5 -3.7 90) (size 0.3 1.55) (layers "B.Cu" "B.Paste" "B.Mask")
      (net 635 "unconnected-(U15-Pad36)") (pinfunction "NC") (pintype "no_connect"))
    (pad "37" smd rect locked (at -0.25 3.848 90) (size 0.3 1.55) (layers "B.Cu" "B.Paste" "B.Mask")
      (net 634 "unconnected-(U15-Pad37)") (pinfunction "PET1_P") (pintype "passive+no_connect"))
    (pad "38" smd rect locked (at 0 -3.7 90) (size 0.3 1.55) (layers "B.Cu" "B.Paste" "B.Mask")
      (net 633 "unconnected-(U15-Pad38)") (pinfunction "NC") (pintype "no_connect"))
    (pad "39" smd rect locked (at 0.246 3.848 90) (size 0.3 1.55) (layers "B.Cu" "B.Paste" "B.Mask")
      (net 1 "GND") (pinfunction "GND") (pintype "passive"))
    (pad "40" smd rect locked (at 0.496 -3.7 90) (size 0.3 1.55) (layers "B.Cu" "B.Paste" "B.Mask")
      (net 416 "Net-(TP43-Pad1)") (pinfunction "SMB_CLK") (pintype "passive"))
    (pad "41" smd rect locked (at 0.747 3.848 90) (size 0.3 1.55) (layers "B.Cu" "B.Paste" "B.Mask")
      (net 125 "PCIE0_RX_N") (pinfunction "PER0_N") (pintype "passive"))
    (pad "42" smd rect locked (at 0.996 -3.7 90) (size 0.3 1.55) (layers "B.Cu" "B.Paste" "B.Mask")
      (net 415 "Net-(TP42-Pad1)") (pinfunction "SMB_DATA") (pintype "passive"))
    (pad "43" smd rect locked (at 1.249 3.848 90) (size 0.3 1.55) (layers "B.Cu" "B.Paste" "B.Mask")
      (net 123 "PCIE0_RX_P") (pinfunction "PER0_P") (pintype "passive"))
    (pad "44" smd rect locked (at 1.499 -3.7 90) (size 0.3 1.55) (layers "B.Cu" "B.Paste" "B.Mask")
      (net 121 "M2_ALERT") (pinfunction "ALERT") (pintype "passive"))
    (pad "45" smd rect locked (at 1.749 3.848 90) (size 0.3 1.55) (layers "B.Cu" "B.Paste" "B.Mask")
      (net 1 "GND") (pinfunction "GND") (pintype "passive"))
    (pad "46" smd rect locked (at 1.999 -3.7 90) (size 0.3 1.55) (layers "B.Cu" "B.Paste" "B.Mask")
      (net 632 "unconnected-(U15-Pad46)") (pinfunction "NC") (pintype "no_connect"))
    (pad "47" smd rect locked (at 2.249 3.848 90) (size 0.3 1.55) (layers "B.Cu" "B.Paste" "B.Mask")
      (net 111 "/M2/C_PCIE0_TX0_N") (pinfunction "PET0_N") (pintype "passive"))
    (pad "48" smd rect locked (at 2.499 -3.7 90) (size 0.3 1.55) (layers "B.Cu" "B.Paste" "B.Mask")
      (net 631 "unconnected-(U15-Pad48)") (pinfunction "NC") (pintype "no_connect"))
    (pad "49" smd rect locked (at 2.749 3.848 90) (size 0.3 1.55) (layers "B.Cu" "B.Paste" "B.Mask")
      (net 109 "/M2/C_PCIE0_TX0_P") (pinfunction "PET0_P") (pintype "passive"))
    (pad "50" smd rect locked (at 2.999 -3.7 90) (size 0.3 1.55) (layers "B.Cu" "B.Paste" "B.Mask")
      (net 124 "PCIE0_RST_N") (pinfunction "PERST#") (pintype "passive"))
    (pad "51" smd rect locked (at 3.249 3.848 90) (size 0.3 1.55) (layers "B.Cu" "B.Paste" "B.Mask")
      (net 1 "GND") (pinfunction "GND") (pintype "passive"))
    (pad "52" smd rect locked (at 3.499 -3.7 90) (size 0.3 1.55) (layers "B.Cu" "B.Paste" "B.Mask")
      (net 120 "PCIE0_CLKREQ_N") (pinfunction "CLKREQ#") (pintype "passive"))
    (pad "53" smd rect locked (at 3.749 3.848 90) (size 0.3 1.55) (layers "B.Cu" "B.Paste" "B.Mask")
      (net 126 "PCIE0_REFCLK_N") (pinfunction "REFCLK_N") (pintype "passive"))
    (pad "54" smd rect locked (at 3.999 -3.7 90) (size 0.3 1.55) (layers "B.Cu" "B.Paste" "B.Mask")
      (net 119 "PCIE0_WAKE_N") (pinfunction "PEWAKE#") (pintype "passive"))
    (pad "55" smd rect locked (at 4.248 3.848 90) (size 0.3 1.55) (layers "B.Cu" "B.Paste" "B.Mask")
      (net 122 "PCIE0_REFCLK_P") (pinfunction "REFCLK_P") (pintype "passive"))
    (pad "56" smd rect locked (at 4.498 -3.7 90) (size 0.3 1.55) (layers "B.Cu" "B.Paste" "B.Mask")
      (net 630 "unconnected-(U15-Pad56)") (pinfunction "NC") (pintype "no_connect"))
    (pad "57" smd rect locked (at 4.748 3.848 90) (size 0.3 1.55) (layers "B.Cu" "B.Paste" "B.Mask")
      (net 1 "GND") (pinfunction "GND") (pintype "passive"))
    (pad "58" smd rect locked (at 4.998 -3.7 90) (size 0.3 1.55) (layers "B.Cu" "B.Paste" "B.Mask")
      (net 629 "unconnected-(U15-Pad58)") (pinfunction "NC") (pintype "no_connect"))
    (pad "67" smd rect locked (at 7.249 3.848 90) (size 0.3 1.55) (layers "B.Cu" "B.Paste" "B.Mask")
      (net 628 "unconnected-(U15-Pad67)") (pinfunction "NC") (pintype "no_connect"))
    (pad "68" smd rect locked (at 7.498 -3.7 90) (size 0.3 1.55) (layers "B.Cu" "B.Paste" "B.Mask")
      (net 627 "unconnected-(U15-Pad68)") (pinfunction "SUSCLK") (pintype "passive+no_connect"))
    (pad "69" smd rect locked (at 7.748 3.848 90) (size 0.3 1.55) (layers "B.Cu" "B.Paste" "B.Mask")
      (net 626 "unconnected-(U15-Pad69)") (pinfunction "NC") (pintype "no_connect"))
    (pad "70" smd rect locked (at 7.998 -3.7 90) (size 0.3 1.55) (layers "B.Cu" "B.Paste" "B.Mask")
      (net 131 "3V3_SYS") (pinfunction "3V3") (pintype "passive"))
    (pad "71" smd rect locked (at 8.249 3.848 90) (size 0.3 1.55) (layers "B.Cu" "B.Paste" "B.Mask")
      (net 1 "GND") (pinfunction "GND") (pintype "passive"))
    (pad "72" smd rect locked (at 8.499 -3.7 90) (size 0.3 1.55) (layers "B.Cu" "B.Paste" "B.Mask")
      (net 131 "3V3_SYS") (pinfunction "3V3") (pintype "passive"))
    (pad "73" smd rect locked (at 8.749 3.848 90) (size 0.3 1.55) (layers "B.Cu" "B.Paste" "B.Mask")
      (net 1 "GND") (pinfunction "GND") (pintype "passive"))
    (pad "74" smd rect locked (at 8.999 -3.7 90) (size 0.3 1.55) (layers "B.Cu" "B.Paste" "B.Mask")
      (net 131 "3V3_SYS") (pinfunction "3V3") (pintype "passive"))
    (pad "75" smd rect locked (at 9.249 3.848 90) (size 0.3 1.55) (layers "B.Cu" "B.Paste" "B.Mask")
      (net 1 "GND") (pinfunction "GND") (pintype "passive"))
    (pad "SH1" smd rect locked (at -10.35 3.073 90) (size 1.2 2.75) (layers "B.Cu" "B.Paste" "B.Mask")
      (net 1 "GND") (pinfunction "SHIELD") (pintype "passive"))
    (pad "SH2" smd rect locked (at 10.348 3.073 90) (size 1.2 2.75) (layers "B.Cu" "B.Paste" "B.Mask")
      (net 1 "GND") (pinfunction "SHIELD") (pintype "passive"))
  )
	(footprint "sa800u-baseboard-hw-footprints:TP_SMD_0.75mm" (layer "B.Cu")
    (tedit 5E4A9375)
    (at 139.6 100)
    (property "Author" "Antmicro")
    (property "License" "Apache-2.0")
    (property "MPN" "")
    (property "Manufacturer" "")
    (property "Sheetfile" "m2.kicad_sch")
    (property "Sheetname" "M2")
    (attr smd)
    (fp_text reference "TP42" (at -0.29 1.04 180) (layer "B.SilkS")
      (effects (font (size 0.7 0.7) (thickness 0.15)) (justify left bottom mirror))
    )
    (fp_text value "TP_0.75mm_SMD" (at 0 -1.2 180) (layer "B.Fab")
      (effects (font (size 0.7 0.7) (thickness 0.15)) (justify left bottom mirror))
    )
    (fp_text user "Author: Antmicro" (at -0.4 -3.901 180) (layer "B.Fab") hide
      (effects (font (size 0.7 0.7) (thickness 0.15)) (justify left bottom mirror))
    )
    (fp_text user "${REFERENCE}" (at -0.4 -2.7 180) (layer "B.Fab") hide
      (effects (font (size 0.7 0.7) (thickness 0.15)) (justify left bottom mirror))
    )
    (fp_text user "License: Apache-2.0" (at -0.4 -5.101 180) (layer "B.Fab") hide
      (effects (font (size 0.7 0.7) (thickness 0.15)) (justify left bottom mirror))
    )
    (pad "1" smd circle (at 0 0) (size 0.75 0.75) (layers "B.Cu" "B.Mask")
      (net 415 "Net-(TP42-Pad1)") (pinfunction "1") (pintype "passive"))
  )
	(footprint "sa800u-baseboard-hw-footprints:TP_SMD_0.75mm" (layer "B.Cu")
    (tedit 5E4A9375)
    (at 139.6 101.4)
    (property "Author" "Antmicro")
    (property "License" "Apache-2.0")
    (property "MPN" "")
    (property "Manufacturer" "")
    (property "Sheetfile" "m2.kicad_sch")
    (property "Sheetname" "M2")
    (attr smd)
    (fp_text reference "TP43" (at -0.29 1.04 180) (layer "B.SilkS")
      (effects (font (size 0.7 0.7) (thickness 0.15)) (justify left bottom mirror))
    )
    (fp_text value "TP_0.75mm_SMD" (at 0 -1.2 180) (layer "B.Fab")
      (effects (font (size 0.7 0.7) (thickness 0.15)) (justify left bottom mirror))
    )
    (fp_text user "${REFERENCE}" (at -0.4 -2.7 180) (layer "B.Fab") hide
      (effects (font (size 0.7 0.7) (thickness 0.15)) (justify left bottom mirror))
    )
    (fp_text user "Author: Antmicro" (at -0.4 -3.901 180) (layer "B.Fab") hide
      (effects (font (size 0.7 0.7) (thickness 0.15)) (justify left bottom mirror))
    )
    (fp_text user "License: Apache-2.0" (at -0.4 -5.101 180) (layer "B.Fab") hide
      (effects (font (size 0.7 0.7) (thickness 0.15)) (justify left bottom mirror))
    )
    (pad "1" smd circle (at 0 0) (size 0.75 0.75) (layers "B.Cu" "B.Mask")
      (net 416 "Net-(TP43-Pad1)") (pinfunction "1") (pintype "passive"))
  )
	(footprint "sa800u-baseboard-hw-footprints:TP_SMD_0.75mm" (layer "B.Cu")
    (tedit 5E4A9375)
    (at 95.6 98.8)
    (property "Author" "Antmicro")
    (property "License" "Apache-2.0")
    (property "MPN" "")
    (property "Manufacturer" "")
    (property "Sheetfile" "ethernet-controller.kicad_sch")
    (property "Sheetname" "Ethernet Controller")
    (attr smd)
    (fp_text reference "TP1" (at 0.59 -0.41 180) (layer "B.SilkS")
      (effects (font (size 0.7 0.7) (thickness 0.15)) (justify left bottom mirror))
    )
    (fp_text value "TP_0.75mm_SMD" (at 0 -1.2 180) (layer "B.Fab")
      (effects (font (size 0.7 0.7) (thickness 0.15)) (justify left bottom mirror))
    )
    (fp_text user "License: Apache-2.0" (at -0.4 -5.101 180) (layer "B.Fab") hide
      (effects (font (size 0.7 0.7) (thickness 0.15)) (justify left bottom mirror))
    )
    (fp_text user "${REFERENCE}" (at -0.4 -2.7 180) (layer "B.Fab") hide
      (effects (font (size 0.7 0.7) (thickness 0.15)) (justify left bottom mirror))
    )
    (fp_text user "Author: Antmicro" (at -0.4 -3.901 180) (layer "B.Fab") hide
      (effects (font (size 0.7 0.7) (thickness 0.15)) (justify left bottom mirror))
    )
    (pad "1" smd circle (at 0 0) (size 0.75 0.75) (layers "B.Cu" "B.Mask")
      (net 177 "/Ethernet Controller/ETH_3V3") (pinfunction "1") (pintype "passive"))
  )
)
